# T6G (Grand Teton) — schematic netlist excerpt (pin names and nets, part order shuffled) for the footprints in the layout excerpt that follows; sources: Cadence DE-HDL packaged netlist, KiCad conversion of 04192023_DAF0TMB3IC0_F0TG_MB_C_brd_V02_OCP.brd

C2275  Q_CAP  22UF 4V 20% X6S  pkg C0402  page 72 : A = PVDD11_S3_P1 ; B = GND
R1591  Q_RES  49.9 1% CHIP  pkg 0402LF  page 109 : A = I3C_SPD_DDRGL_CPU1_SCL ; B = I3C_SPD_DDRL_CPU1_SCL

(kicad_pcb
	(version 20260206)
	(generator "pcbnew")
	(generator_version "10.0")
	(general
		(thickness 1.6)
		(legacy_teardrops no)
	)
	(paper "A4")
	(title_block
		(title "04192023_DAF0TMB3IC0_F0TG_MB_C_brd_V02_OCP.brd")
		(comment 1 "Grand Teton / footprints 7391-7392 of 8354")
	)
	(layers
		(0 "F.Cu" signal "TOP")
		(4 "In1.Cu" signal "GND")
		(6 "In2.Cu" signal "IN1")
		(8 "In3.Cu" signal "GND1")
		(10 "In4.Cu" signal "IN2")
		(12 "In5.Cu" signal "GND2")
		(14 "In6.Cu" signal "IN3")
		(16 "In7.Cu" signal "GND3")
		(18 "In8.Cu" signal "VCC")
		(20 "In9.Cu" signal "VCC1")
		(22 "In10.Cu" signal "GND4")
		(24 "In11.Cu" signal "IN4")
		(26 "In12.Cu" signal "GND5")
		(28 "In13.Cu" signal "IN5")
		(30 "In14.Cu" signal "GND6")
		(32 "In15.Cu" signal "IN6")
		(34 "In16.Cu" signal "GND7")
		(2 "B.Cu" signal "BOTTOM")
		(9 "F.Adhes" user "F.Adhesive")
		(11 "B.Adhes" user "B.Adhesive")
		(13 "F.Paste" user "Package Geometry/Pastemask Top")
		(15 "B.Paste" user "Package Geometry/Pastemask Bottom")
		(5 "F.SilkS" user "Ref Des/Silkscreen Top")
		(7 "B.SilkS" user "Ref Des/Silkscreen Bottom")
		(1 "F.Mask" user "Board Geometry/Soldermask Top")
		(3 "B.Mask" user "Board Geometry/Soldermask Bottom")
		(17 "Dwgs.User" user "User.Drawings")
		(19 "Cmts.User" user "User.Comments")
		(21 "Eco1.User" user "User.Eco1")
		(23 "Eco2.User" user "User.Eco2")
		(25 "Edge.Cuts" user "Board Geometry/Outline")
		(27 "Margin" user)
		(31 "F.CrtYd" user "Package Geometry/Place Bound Top")
		(29 "B.CrtYd" user "Package Geometry/Place Bound Bottom")
		(35 "F.Fab" user "Ref Des/Assembly Top")
		(33 "B.Fab" user "Ref Des/Assembly Bottom")
	)
	(footprint ""
		(layer "B.Cu")
		(at 206.22133 -194.98691)
		(property "Reference" "R1591"
			(at 0 0 0)
			(layer "B.SilkS")
			(hide yes)
			(effects
				(font
					(size 1.27 1.27)
				)
				(justify mirror)
			)
		)
		(property "Value" ""
			(at 0 0 0)
			(layer "B.Fab")
			(effects
				(font
					(size 1.27 1.27)
				)
				(justify mirror)
			)
		)
		(duplicate_pad_numbers_are_jumpers no)
		(fp_line
			(start -0.7874 -0.4064)
			(end -0.7874 0.4064)
			(stroke
				(width 0.1524)
				(type default)
			)
			(layer "B.SilkS")
		)
		(fp_line
			(start -0.7874 0.4064)
			(end 0.7874 0.4064)
			(stroke
				(width 0.1524)
				(type default)
			)
			(layer "B.SilkS")
		)
		(fp_line
			(start 0.7874 -0.4064)
			(end -0.7874 -0.4064)
			(stroke
				(width 0.1524)
				(type default)
			)
			(layer "B.SilkS")
		)
		(fp_line
			(start 0.7874 0.4064)
			(end 0.7874 -0.4064)
			(stroke
				(width 0.1524)
				(type default)
			)
			(layer "B.SilkS")
		)
		(fp_line
			(start -0.67945 -0.3048)
			(end -0.67945 0.3048)
			(stroke
				(width 0.1)
				(type default)
			)
			(layer "B.Fab")
		)
		(fp_line
			(start -0.67945 0.3048)
			(end -0.120396 0.3048)
			(stroke
				(width 0.1)
				(type default)
			)
			(layer "B.Fab")
		)
		(fp_line
			(start -0.12065 -0.3048)
			(end -0.67945 -0.3048)
			(stroke
				(width 0.1)
				(type default)
			)
			(layer "B.Fab")
		)
		(fp_line
			(start -0.12065 -0.2794)
			(end -0.12065 -0.3048)
			(stroke
				(width 0.1)
				(type default)
			)
			(layer "B.Fab")
		)
		(fp_line
			(start -0.120396 0.2794)
			(end 0.12065 0.2794)
			(stroke
				(width 0.1)
				(type default)
			)
			(layer "B.Fab")
		)
		(fp_line
			(start -0.120396 0.3048)
			(end -0.120396 0.2794)
			(stroke
				(width 0.1)
				(type default)
			)
			(layer "B.Fab")
		)
		(fp_line
			(start 0.12065 -0.305054)
			(end 0.12065 -0.2794)
			(stroke
				(width 0.1)
				(type default)
			)
			(layer "B.Fab")
		)
		(fp_line
			(start 0.12065 -0.2794)
			(end -0.12065 -0.2794)
			(stroke
				(width 0.1)
				(type default)
			)
			(layer "B.Fab")
		)
		(fp_line
			(start 0.12065 0.2794)
			(end 0.12065 0.3048)
			(stroke
				(width 0.1)
				(type default)
			)
			(layer "B.Fab")
		)
		(fp_line
			(start 0.12065 0.3048)
			(end 0.67945 0.3048)
			(stroke
				(width 0.1)
				(type default)
			)
			(layer "B.Fab")
		)
		(fp_line
			(start 0.67945 -0.305054)
			(end 0.12065 -0.305054)
			(stroke
				(width 0.1)
				(type default)
			)
			(layer "B.Fab")
		)
		(fp_line
			(start 0.67945 0.3048)
			(end 0.67945 -0.305054)
			(stroke
				(width 0.1)
				(type default)
			)
			(layer "B.Fab")
		)
		(pad "1" smd circle
			(at 0.40005 0 180)
			(size 0 0)
			(layers "B.Cu" "B.Mask" "B.Paste")
			(net "I3C_SPD_DDRGL_CPU1_SCL")
		)
		(pad "2" smd circle
			(at -0.40005 0 180)
			(size 0 0)
			(layers "B.Cu" "B.Mask" "B.Paste")
			(net "I3C_SPD_DDRL_CPU1_SCL")
		)
	)
	(footprint ""
		(layer "B.Cu")
		(at 113.959386 -266.005564)
		(property "Reference" "C2275"
			(at 0 0 0)
			(layer "B.SilkS")
			(hide yes)
			(effects
				(font
					(size 1.27 1.27)
				)
				(justify mirror)
			)
		)
		(property "Value" ""
			(at 0 0 0)
			(layer "B.Fab")
			(effects
				(font
					(size 1.27 1.27)
				)
				(justify mirror)
			)
		)
		(duplicate_pad_numbers_are_jumpers no)
		(fp_line
			(start -0.7874 -0.4064)
			(end -0.7874 0.4064)
			(stroke
				(width 0.1524)
				(type default)
			)
			(layer "B.SilkS")
		)
		(fp_line
			(start -0.7874 0.4064)
			(end 0.7874 0.4064)
			(stroke
				(width 0.1524)
				(type default)
			)
			(layer "B.SilkS")
		)
		(fp_line
			(start 0.7874 -0.4064)
			(end -0.7874 -0.4064)
			(stroke
				(width 0.1524)
				(type default)
			)
			(layer "B.SilkS")
		)
		(fp_line
			(start 0.7874 0.4064)
			(end 0.7874 -0.4064)
			(stroke
				(width 0.1524)
				(type default)
			)
			(layer "B.SilkS")
		)
		(fp_line
			(start -0.67945 -0.3048)
			(end -0.67945 0.3048)
			(stroke
				(width 0.1)
				(type default)
			)
			(layer "B.Fab")
		)
		(fp_line
			(start -0.67945 0.3048)
			(end -0.120396 0.3048)
			(stroke
				(width 0.1)
				(type default)
			)
			(layer "B.Fab")
		)
		(fp_line
			(start -0.12065 -0.3048)
			(end -0.67945 -0.3048)
			(stroke
				(width 0.1)
				(type default)
			)
			(layer "B.Fab")
		)
		(fp_line
			(start -0.12065 -0.2794)
			(end -0.12065 -0.3048)
			(stroke
				(width 0.1)
				(type default)
			)
			(layer "B.Fab")
		)
		(fp_line
			(start -0.120396 0.2794)
			(end 0.12065 0.2794)
			(stroke
				(width 0.1)
				(type default)
			)
			(layer "B.Fab")
		)
		(fp_line
			(start -0.120396 0.3048)
			(end -0.120396 0.2794)
			(stroke
				(width 0.1)
				(type default)
			)
			(layer "B.Fab")
		)
		(fp_line
			(start 0.12065 -0.305054)
			(end 0.12065 -0.2794)
			(stroke
				(width 0.1)
				(type default)
			)
			(layer "B.Fab")
		)
		(fp_line
			(start 0.12065 -0.2794)
			(end -0.12065 -0.2794)
			(stroke
				(width 0.1)
				(type default)
			)
			(layer "B.Fab")
		)
		(fp_line
			(start 0.12065 0.2794)
			(end 0.12065 0.3048)
			(stroke
				(width 0.1)
				(type default)
			)
			(layer "B.Fab")
		)
		(fp_line
			(start 0.12065 0.3048)
			(end 0.67945 0.3048)
			(stroke
				(width 0.1)
				(type default)
			)
			(layer "B.Fab")
		)
		(fp_line
			(start 0.67945 -0.305054)
			(end 0.12065 -0.305054)
			(stroke
				(width 0.1)
				(type default)
			)
			(layer "B.Fab")
		)
		(fp_line
			(start 0.67945 0.3048)
			(end 0.67945 -0.305054)
			(stroke
				(width 0.1)
				(type default)
			)
			(layer "B.Fab")
		)
		(pad "1" smd circle
			(at 0.40005 0 180)
			(size 0 0)
			(layers "B.Cu" "B.Mask" "B.Paste")
			(net "PVDD11_S3_P1")
		)
		(pad "2" smd circle
			(at -0.40005 0 180)
			(size 0 0)
			(layers "B.Cu" "B.Mask" "B.Paste")
			(net "GND")
		)
	)
)
